(kicad_pcb
	(version 20260206)
	(generator "pcbnew")
	(generator_version "10.0")
	(general
		(thickness 1.6)
		(legacy_teardrops no)
	)
	(paper "A4")
	(title_block
		(title "peb — Lightning_PEB_BRD.brd")
		(comment 1 "Lightning (Wiwynn / Facebook NVMe JBOF) / footprints 1125-1132 of 2563")
	)
	(layers
		(0 "F.Cu" signal "TOP")
		(4 "In1.Cu" signal "L2GND")
		(6 "In2.Cu" signal "L3")
		(8 "In3.Cu" signal "L4VCC")
		(10 "In4.Cu" signal "L5VCC")
		(12 "In5.Cu" signal "L6")
		(14 "In6.Cu" signal "L7GND")
		(2 "B.Cu" signal "BOTTOM")
		(9 "F.Adhes" user "F.Adhesive")
		(11 "B.Adhes" user "B.Adhesive")
		(13 "F.Paste" user "Package Geometry/Pastemask Top")
		(15 "B.Paste" user "Package Geometry/Pastemask Bottom")
		(5 "F.SilkS" user "Ref Des/Silkscreen Top")
		(7 "B.SilkS" user "Ref Des/Silkscreen Bottom")
		(1 "F.Mask" user "Board Geometry/Soldermask Top")
		(3 "B.Mask" user "Board Geometry/Soldermask Bottom")
		(17 "Dwgs.User" user "User.Drawings")
		(19 "Cmts.User" user "User.Comments")
		(21 "Eco1.User" user "User.Eco1")
		(23 "Eco2.User" user "User.Eco2")
		(25 "Edge.Cuts" user "Board Geometry/Outline")
		(27 "Margin" user)
		(31 "F.CrtYd" user "Package Geometry/Place Bound Top")
		(29 "B.CrtYd" user "Package Geometry/Place Bound Bottom")
		(35 "F.Fab" user "Ref Des/Assembly Top")
		(33 "B.Fab" user "Ref Des/Assembly Bottom")
	)
	(footprint ""
		(layer "F.Cu")
		(at 92.391992 -212.420454 180)
		(property "Reference" "C378"
			(at 0 0 180)
			(layer "F.SilkS")
			(hide yes)
			(effects
				(font
					(size 1.27 1.27)
				)
			)
		)
		(property "Value" "SCD22U10V2KX-1GP"
			(at 1.1811 -2.7051 180)
			(unlocked yes)
			(layer "F.Fab")
			(hide yes)
			(effects
				(font
					(size 1.016 1.016)
					(thickness 0.1524)
				)
			)
		)
		(property "Device Type" "C402H22"
			(at 1.1811 -4.2291 180)
			(unlocked yes)
			(layer "F.Fab")
			(hide yes)
			(effects
				(font
					(size 1.016 1.016)
					(thickness 0.1524)
				)
			)
		)
		(duplicate_pad_numbers_are_jumpers no)
		(fp_rect
			(start -0.4318 0.9525)
			(end 0.4318 -0.9525)
			(stroke
				(width 0)
				(type default)
			)
			(fill no)
			(layer "F.CrtYd")
		)
		(fp_rect
			(start -0.4318 0.9525)
			(end 0.4318 -0.9525)
			(stroke
				(width 0)
				(type default)
			)
			(fill no)
			(layer "F.Fab")
		)
		(pad "1" smd custom
			(at 0 -0.4445 180)
			(size 0.1524 0.1524)
			(layers "F.Cu" "F.Mask" "F.Paste")
			(net "PCIE_TX_CAP_P64")
			(options
				(clearance outline)
				(anchor circle)
			)
			(primitives
				(gr_poly
					(pts
						(arc
							(start 0.3048 -0.2032)
							(mid 0.275042 -0.275042)
							(end 0.2032 -0.3048)
						)
						(arc
							(start -0.2032 -0.3048)
							(mid -0.275042 -0.275042)
							(end -0.3048 -0.2032)
						)
						(arc
							(start -0.3048 0.2032)
							(mid -0.275042 0.275042)
							(end -0.2032 0.3048)
						)
						(arc
							(start 0.2032 0.3048)
							(mid 0.275042 0.275042)
							(end 0.3048 0.2032)
						)
					)
					(width 0)
					(fill yes)
				)
			)
		)
		(pad "2" smd custom
			(at 0 0.4445 180)
			(size 0.1524 0.1524)
			(layers "F.Cu" "F.Mask" "F.Paste")
			(net "PCIE_TX_P64")
			(options
				(clearance outline)
				(anchor circle)
			)
			(primitives
				(gr_poly
					(pts
						(arc
							(start 0.3048 -0.2032)
							(mid 0.275042 -0.275042)
							(end 0.2032 -0.3048)
						)
						(arc
							(start -0.2032 -0.3048)
							(mid -0.275042 -0.275042)
							(end -0.3048 -0.2032)
						)
						(arc
							(start -0.3048 0.2032)
							(mid -0.275042 0.275042)
							(end -0.2032 0.3048)
						)
						(arc
							(start 0.2032 0.3048)
							(mid 0.275042 0.275042)
							(end 0.3048 0.2032)
						)
					)
					(width 0)
					(fill yes)
				)
			)
		)
	)
	(footprint ""
		(layer "F.Cu")
		(at 187.192158 -212.420454 180)
		(property "Reference" "C125"
			(at 0 0 180)
			(layer "F.SilkS")
			(hide yes)
			(effects
				(font
					(size 1.27 1.27)
				)
			)
		)
		(property "Value" "SCD22U10V2KX-1GP"
			(at 1.1811 -2.7051 180)
			(unlocked yes)
			(layer "F.Fab")
			(hide yes)
			(effects
				(font
					(size 1.016 1.016)
					(thickness 0.1524)
				)
			)
		)
		(property "Device Type" "C402H22"
			(at 1.1811 -4.2291 180)
			(unlocked yes)
			(layer "F.Fab")
			(hide yes)
			(effects
				(font
					(size 1.016 1.016)
					(thickness 0.1524)
				)
			)
		)
		(duplicate_pad_numbers_are_jumpers no)
		(fp_rect
			(start -0.4318 0.9525)
			(end 0.4318 -0.9525)
			(stroke
				(width 0)
				(type default)
			)
			(fill no)
			(layer "F.CrtYd")
		)
		(fp_rect
			(start -0.4318 0.9525)
			(end 0.4318 -0.9525)
			(stroke
				(width 0)
				(type default)
			)
			(fill no)
			(layer "F.Fab")
		)
		(pad "1" smd custom
			(at 0 -0.4445 180)
			(size 0.1524 0.1524)
			(layers "F.Cu" "F.Mask" "F.Paste")
			(net "PCIE_TX_CAP_P46")
			(options
				(clearance outline)
				(anchor circle)
			)
			(primitives
				(gr_poly
					(pts
						(arc
							(start 0.3048 -0.2032)
							(mid 0.275042 -0.275042)
							(end 0.2032 -0.3048)
						)
						(arc
							(start -0.2032 -0.3048)
							(mid -0.275042 -0.275042)
							(end -0.3048 -0.2032)
						)
						(arc
							(start -0.3048 0.2032)
							(mid -0.275042 0.275042)
							(end -0.2032 0.3048)
						)
						(arc
							(start 0.2032 0.3048)
							(mid 0.275042 0.275042)
							(end 0.3048 0.2032)
						)
					)
					(width 0)
					(fill yes)
				)
			)
		)
		(pad "2" smd custom
			(at 0 0.4445 180)
			(size 0.1524 0.1524)
			(layers "F.Cu" "F.Mask" "F.Paste")
			(net "PCIE_TX_P46")
			(options
				(clearance outline)
				(anchor circle)
			)
			(primitives
				(gr_poly
					(pts
						(arc
							(start 0.3048 -0.2032)
							(mid 0.275042 -0.275042)
							(end 0.2032 -0.3048)
						)
						(arc
							(start -0.2032 -0.3048)
							(mid -0.275042 -0.275042)
							(end -0.3048 -0.2032)
						)
						(arc
							(start -0.3048 0.2032)
							(mid -0.275042 0.275042)
							(end -0.2032 0.3048)
						)
						(arc
							(start 0.2032 0.3048)
							(mid 0.275042 0.275042)
							(end 0.3048 0.2032)
						)
					)
					(width 0)
					(fill yes)
				)
			)
		)
	)
	(footprint ""
		(layer "F.Cu")
		(at 25.96896 -80.1751 90)
		(property "Reference" "R383"
			(at 0 0 90)
			(layer "F.SilkS")
			(hide yes)
			(effects
				(font
					(size 1.27 1.27)
				)
			)
		)
		(property "Value" "0R2J-2-GP"
			(at 0.064008 -3.993896 90)
			(unlocked yes)
			(layer "F.Fab")
			(hide yes)
			(effects
				(font
					(size 1.016 1.016)
					(thickness 0.1524)
				)
			)
		)
		(property "Device Type" "R402H16"
			(at 0.064008 -5.517896 90)
			(unlocked yes)
			(layer "F.Fab")
			(hide yes)
			(effects
				(font
					(size 1.016 1.016)
					(thickness 0.1524)
				)
			)
		)
		(duplicate_pad_numbers_are_jumpers no)
		(fp_line
			(start 0.508 -0.9398)
			(end -0.508 -0.9398)
			(stroke
				(width 0.1524)
				(type default)
			)
			(layer "F.SilkS")
		)
		(fp_line
			(start -0.508 -0.9398)
			(end -0.508 0.9398)
			(stroke
				(width 0.1524)
				(type default)
			)
			(layer "F.SilkS")
		)
		(fp_rect
			(start -0.508 0.9398)
			(end 0.508 -0.9398)
			(stroke
				(width 0)
				(type default)
			)
			(fill no)
			(layer "F.CrtYd")
		)
		(fp_rect
			(start -0.508 0.9398)
			(end 0.508 -0.9398)
			(stroke
				(width 0)
				(type default)
			)
			(fill no)
			(layer "F.Fab")
		)
		(pad "1" smd custom
			(at 0 -0.4445 90)
			(size 0.1397 0.1397)
			(layers "F.Cu" "F.Mask" "F.Paste")
			(net "NVM_SI")
			(options
				(clearance outline)
				(anchor circle)
			)
			(primitives
				(gr_poly
					(pts
						(arc
							(start -0.1778 -0.2794)
							(mid -0.249642 -0.249642)
							(end -0.2794 -0.1778)
						)
						(arc
							(start -0.2794 0.1778)
							(mid -0.249642 0.249642)
							(end -0.1778 0.2794)
						)
						(arc
							(start 0.1778 0.2794)
							(mid 0.249642 0.249642)
							(end 0.2794 0.1778)
						)
						(arc
							(start 0.2794 -0.1778)
							(mid 0.249642 -0.249642)
							(end 0.1778 -0.2794)
						)
					)
					(width 0)
					(fill yes)
				)
			)
		)
		(pad "2" smd custom
			(at 0 0.4445 90)
			(size 0.1397 0.1397)
			(layers "F.Cu" "F.Mask" "F.Paste")
			(net "I210_SI_R")
			(options
				(clearance outline)
				(anchor circle)
			)
			(primitives
				(gr_poly
					(pts
						(arc
							(start -0.1778 -0.2794)
							(mid -0.249642 -0.249642)
							(end -0.2794 -0.1778)
						)
						(arc
							(start -0.2794 0.1778)
							(mid -0.249642 0.249642)
							(end -0.1778 0.2794)
						)
						(arc
							(start 0.1778 0.2794)
							(mid 0.249642 0.249642)
							(end 0.2794 0.1778)
						)
						(arc
							(start 0.2794 -0.1778)
							(mid 0.249642 -0.249642)
							(end 0.1778 -0.2794)
						)
					)
					(width 0)
					(fill yes)
				)
			)
		)
	)
	(footprint ""
		(layer "F.Cu")
		(at 14.4018 -194.2592 180)
		(property "Reference" "R2117"
			(at 0 0 180)
			(layer "F.SilkS")
			(hide yes)
			(effects
				(font
					(size 1.27 1.27)
				)
			)
		)
		(property "Value" "100KR2J-4-GP"
			(at 0.064008 -3.993896 180)
			(unlocked yes)
			(layer "F.Fab")
			(hide yes)
			(effects
				(font
					(size 1.016 1.016)
					(thickness 0.1524)
				)
			)
		)
		(property "Device Type" "R402H15"
			(at 0.064008 -5.517896 180)
			(unlocked yes)
			(layer "F.Fab")
			(hide yes)
			(effects
				(font
					(size 1.016 1.016)
					(thickness 0.1524)
				)
			)
		)
		(duplicate_pad_numbers_are_jumpers no)
		(fp_line
			(start 0.508 -0.9398)
			(end -0.508 -0.9398)
			(stroke
				(width 0.1524)
				(type default)
			)
			(layer "F.SilkS")
		)
		(fp_line
			(start -0.508 -0.9398)
			(end -0.508 0.9398)
			(stroke
				(width 0.1524)
				(type default)
			)
			(layer "F.SilkS")
		)
		(fp_rect
			(start -0.508 0.9398)
			(end 0.508 -0.9398)
			(stroke
				(width 0)
				(type default)
			)
			(fill no)
			(layer "F.CrtYd")
		)
		(fp_rect
			(start -0.508 0.9398)
			(end 0.508 -0.9398)
			(stroke
				(width 0)
				(type default)
			)
			(fill no)
			(layer "F.Fab")
		)
		(pad "1" smd custom
			(at 0 -0.4445 180)
			(size 0.1397 0.1397)
			(layers "F.Cu" "F.Mask" "F.Paste")
			(net "MB0_VCAP_R")
			(options
				(clearance outline)
				(anchor circle)
			)
			(primitives
				(gr_poly
					(pts
						(arc
							(start -0.1778 -0.2794)
							(mid -0.249642 -0.249642)
							(end -0.2794 -0.1778)
						)
						(arc
							(start -0.2794 0.1778)
							(mid -0.249642 0.249642)
							(end -0.1778 0.2794)
						)
						(arc
							(start 0.1778 0.2794)
							(mid 0.249642 0.249642)
							(end 0.2794 0.1778)
						)
						(arc
							(start 0.2794 -0.1778)
							(mid 0.249642 -0.249642)
							(end 0.1778 -0.2794)
						)
					)
					(width 0)
					(fill yes)
				)
			)
		)
		(pad "2" smd custom
			(at 0 0.4445 180)
			(size 0.1397 0.1397)
			(layers "F.Cu" "F.Mask" "F.Paste")
			(net "MB0_ISET_R")
			(options
				(clearance outline)
				(anchor circle)
			)
			(primitives
				(gr_poly
					(pts
						(arc
							(start -0.1778 -0.2794)
							(mid -0.249642 -0.249642)
							(end -0.2794 -0.1778)
						)
						(arc
							(start -0.2794 0.1778)
							(mid -0.249642 0.249642)
							(end -0.1778 0.2794)
						)
						(arc
							(start 0.1778 0.2794)
							(mid 0.249642 0.249642)
							(end 0.2794 0.1778)
						)
						(arc
							(start 0.2794 -0.1778)
							(mid 0.249642 -0.249642)
							(end 0.1778 -0.2794)
						)
					)
					(width 0)
					(fill yes)
				)
			)
		)
	)
	(footprint ""
		(layer "F.Cu")
		(at 273.702526 -6.8453 -90)
		(property "Reference" "R2903"
			(at 0 0 270)
			(layer "F.SilkS")
			(hide yes)
			(effects
				(font
					(size 1.27 1.27)
				)
			)
		)
		(property "Value" "0R2J-2-GP"
			(at 0.064008 -3.993896 270)
			(unlocked yes)
			(layer "F.Fab")
			(hide yes)
			(effects
				(font
					(size 1.016 1.016)
					(thickness 0.1524)
				)
			)
		)
		(property "Device Type" "R402H16"
			(at 0.064008 -5.517896 270)
			(unlocked yes)
			(layer "F.Fab")
			(hide yes)
			(effects
				(font
					(size 1.016 1.016)
					(thickness 0.1524)
				)
			)
		)
		(duplicate_pad_numbers_are_jumpers no)
		(fp_line
			(start -0.508 -0.9398)
			(end -0.508 0.9398)
			(stroke
				(width 0.1524)
				(type default)
			)
			(layer "F.SilkS")
		)
		(fp_line
			(start 0.508 -0.9398)
			(end -0.508 -0.9398)
			(stroke
				(width 0.1524)
				(type default)
			)
			(layer "F.SilkS")
		)
		(fp_rect
			(start -0.508 0.9398)
			(end 0.508 -0.9398)
			(stroke
				(width 0)
				(type default)
			)
			(fill no)
			(layer "F.CrtYd")
		)
		(fp_rect
			(start -0.508 0.9398)
			(end 0.508 -0.9398)
			(stroke
				(width 0)
				(type default)
			)
			(fill no)
			(layer "F.Fab")
		)
		(pad "1" smd custom
			(at 0 -0.4445 270)
			(size 0.1397 0.1397)
			(layers "F.Cu" "F.Mask" "F.Paste")
			(net "BMC_I2C12_MINI6_SDA")
			(options
				(clearance outline)
				(anchor circle)
			)
			(primitives
				(gr_poly
					(pts
						(arc
							(start -0.1778 -0.2794)
							(mid -0.249642 -0.249642)
							(end -0.2794 -0.1778)
						)
						(arc
							(start -0.2794 0.1778)
							(mid -0.249642 0.249642)
							(end -0.1778 0.2794)
						)
						(arc
							(start 0.1778 0.2794)
							(mid 0.249642 0.249642)
							(end 0.2794 0.1778)
						)
						(arc
							(start 0.2794 -0.1778)
							(mid 0.249642 -0.249642)
							(end 0.1778 -0.2794)
						)
					)
					(width 0)
					(fill yes)
				)
			)
		)
		(pad "2" smd custom
			(at 0 0.4445 270)
			(size 0.1397 0.1397)
			(layers "F.Cu" "F.Mask" "F.Paste")
			(net "8644_SDA_R_6")
			(options
				(clearance outline)
				(anchor circle)
			)
			(primitives
				(gr_poly
					(pts
						(arc
							(start -0.1778 -0.2794)
							(mid -0.249642 -0.249642)
							(end -0.2794 -0.1778)
						)
						(arc
							(start -0.2794 0.1778)
							(mid -0.249642 0.249642)
							(end -0.1778 0.2794)
						)
						(arc
							(start 0.1778 0.2794)
							(mid 0.249642 0.249642)
							(end 0.2794 0.1778)
						)
						(arc
							(start 0.2794 -0.1778)
							(mid 0.249642 -0.249642)
							(end 0.1778 -0.2794)
						)
					)
					(width 0)
					(fill yes)
				)
			)
		)
	)
	(footprint ""
		(layer "F.Cu")
		(at 162.56 -85.2424)
		(property "Reference" "R3103"
			(at 0 0 0)
			(layer "F.SilkS")
			(hide yes)
			(effects
				(font
					(size 1.27 1.27)
				)
			)
		)
		(property "Value" "27R2F-GP"
			(at 0.064008 -3.993896 0)
			(unlocked yes)
			(layer "F.Fab")
			(hide yes)
			(effects
				(font
					(size 1.016 1.016)
					(thickness 0.1524)
				)
			)
		)
		(property "Device Type" "R402H16"
			(at 0.064008 -5.517896 0)
			(unlocked yes)
			(layer "F.Fab")
			(hide yes)
			(effects
				(font
					(size 1.016 1.016)
					(thickness 0.1524)
				)
			)
		)
		(duplicate_pad_numbers_are_jumpers no)
		(fp_line
			(start -0.508 -0.9398)
			(end -0.508 0.9398)
			(stroke
				(width 0.1524)
				(type default)
			)
			(layer "F.SilkS")
		)
		(fp_line
			(start 0.508 -0.9398)
			(end -0.508 -0.9398)
			(stroke
				(width 0.1524)
				(type default)
			)
			(layer "F.SilkS")
		)
		(fp_rect
			(start -0.508 0.9398)
			(end 0.508 -0.9398)
			(stroke
				(width 0)
				(type default)
			)
			(fill no)
			(layer "F.CrtYd")
		)
		(fp_rect
			(start -0.508 0.9398)
			(end 0.508 -0.9398)
			(stroke
				(width 0)
				(type default)
			)
			(fill no)
			(layer "F.Fab")
		)
		(pad "1" smd custom
			(at 0 -0.4445)
			(size 0.1397 0.1397)
			(layers "F.Cu" "F.Mask" "F.Paste")
			(net "PCIE_REFCLK_D_N_R")
			(options
				(clearance outline)
				(anchor circle)
			)
			(primitives
				(gr_poly
					(pts
						(arc
							(start -0.1778 -0.2794)
							(mid -0.249642 -0.249642)
							(end -0.2794 -0.1778)
						)
						(arc
							(start -0.2794 0.1778)
							(mid -0.249642 0.249642)
							(end -0.1778 0.2794)
						)
						(arc
							(start 0.1778 0.2794)
							(mid 0.249642 0.249642)
							(end 0.2794 0.1778)
						)
						(arc
							(start 0.2794 -0.1778)
							(mid 0.249642 -0.249642)
							(end 0.1778 -0.2794)
						)
					)
					(width 0)
					(fill yes)
				)
			)
		)
		(pad "2" smd custom
			(at 0 0.4445)
			(size 0.1397 0.1397)
			(layers "F.Cu" "F.Mask" "F.Paste")
			(net "PCIE_REFCLK_D_N")
			(options
				(clearance outline)
				(anchor circle)
			)
			(primitives
				(gr_poly
					(pts
						(arc
							(start -0.1778 -0.2794)
							(mid -0.249642 -0.249642)
							(end -0.2794 -0.1778)
						)
						(arc
							(start -0.2794 0.1778)
							(mid -0.249642 0.249642)
							(end -0.1778 0.2794)
						)
						(arc
							(start 0.1778 0.2794)
							(mid 0.249642 0.249642)
							(end 0.2794 0.1778)
						)
						(arc
							(start 0.2794 -0.1778)
							(mid 0.249642 -0.249642)
							(end 0.1778 -0.2794)
						)
					)
					(width 0)
					(fill yes)
				)
			)
		)
	)
	(footprint ""
		(layer "F.Cu")
		(at 32.004 -197.866)
		(property "Reference" "R2111"
			(at 0 0 0)
			(layer "F.SilkS")
			(hide yes)
			(effects
				(font
					(size 1.27 1.27)
				)
			)
		)
		(property "Value" "10R2J-2-GP"
			(at 0.064008 -3.993896 0)
			(unlocked yes)
			(layer "F.Fab")
			(hide yes)
			(effects
				(font
					(size 1.016 1.016)
					(thickness 0.1524)
				)
			)
		)
		(property "Device Type" "R402H14"
			(at 0.064008 -5.517896 0)
			(unlocked yes)
			(layer "F.Fab")
			(hide yes)
			(effects
				(font
					(size 1.016 1.016)
					(thickness 0.1524)
				)
			)
		)
		(duplicate_pad_numbers_are_jumpers no)
		(fp_line
			(start -0.508 -0.9398)
			(end -0.508 0.9398)
			(stroke
				(width 0.1524)
				(type default)
			)
			(layer "F.SilkS")
		)
		(fp_line
			(start 0.508 -0.9398)
			(end -0.508 -0.9398)
			(stroke
				(width 0.1524)
				(type default)
			)
			(layer "F.SilkS")
		)
		(fp_rect
			(start -0.508 0.9398)
			(end 0.508 -0.9398)
			(stroke
				(width 0)
				(type default)
			)
			(fill no)
			(layer "F.CrtYd")
		)
		(fp_rect
			(start -0.508 0.9398)
			(end 0.508 -0.9398)
			(stroke
				(width 0)
				(type default)
			)
			(fill no)
			(layer "F.Fab")
		)
		(pad "1" smd custom
			(at 0 -0.4445)
			(size 0.1397 0.1397)
			(layers "F.Cu" "F.Mask" "F.Paste")
			(net "MB0_12V_CTRL_GATE1")
			(options
				(clearance outline)
				(anchor circle)
			)
			(primitives
				(gr_poly
					(pts
						(arc
							(start -0.1778 -0.2794)
							(mid -0.249642 -0.249642)
							(end -0.2794 -0.1778)
						)
						(arc
							(start -0.2794 0.1778)
							(mid -0.249642 0.249642)
							(end -0.1778 0.2794)
						)
						(arc
							(start 0.1778 0.2794)
							(mid 0.249642 0.249642)
							(end 0.2794 0.1778)
						)
						(arc
							(start 0.2794 -0.1778)
							(mid 0.249642 -0.249642)
							(end 0.1778 -0.2794)
						)
					)
					(width 0)
					(fill yes)
				)
			)
		)
		(pad "2" smd custom
			(at 0 0.4445)
			(size 0.1397 0.1397)
			(layers "F.Cu" "F.Mask" "F.Paste")
			(net "MB0_CM_GATE_R")
			(options
				(clearance outline)
				(anchor circle)
			)
			(primitives
				(gr_poly
					(pts
						(arc
							(start -0.1778 -0.2794)
							(mid -0.249642 -0.249642)
							(end -0.2794 -0.1778)
						)
						(arc
							(start -0.2794 0.1778)
							(mid -0.249642 0.249642)
							(end -0.1778 0.2794)
						)
						(arc
							(start 0.1778 0.2794)
							(mid 0.249642 0.249642)
							(end 0.2794 0.1778)
						)
						(arc
							(start 0.2794 -0.1778)
							(mid 0.249642 -0.249642)
							(end 0.1778 -0.2794)
						)
					)
					(width 0)
					(fill yes)
				)
			)
		)
	)
	(footprint ""
		(layer "F.Cu")
		(at 303.53 -57.0992)
		(property "Reference" "C427"
			(at 0 0 0)
			(layer "F.SilkS")
			(hide yes)
			(effects
				(font
					(size 1.27 1.27)
				)
			)
		)
		(property "Value" "SC10U16V5KX-1-GP"
			(at -0.0762 -6.1214 0)
			(unlocked yes)
			(layer "F.Fab")
			(hide yes)
			(effects
				(font
					(size 1.016 1.016)
					(thickness 0.1524)
				)
			)
		)
		(property "Device Type" "C805H54"
			(at -0.0762 -8.1534 0)
			(unlocked yes)
			(layer "F.Fab")
			(hide yes)
			(effects
				(font
					(size 1.016 1.016)
					(thickness 0.1524)
				)
			)
		)
		(duplicate_pad_numbers_are_jumpers no)
		(fp_line
			(start 0.635 0)
			(end -0.635 0)
			(stroke
				(width 0.508)
				(type default)
			)
			(layer "F.SilkS")
		)
		(fp_rect
			(start -0.9652 1.778)
			(end 0.9652 -1.778)
			(stroke
				(width 0)
				(type default)
			)
			(fill no)
			(layer "F.CrtYd")
		)
		(fp_poly
			(pts
				(xy -0.9652 -1.778) (xy 0.9652 -1.778) (xy 0.9652 1.778) (xy -0.9652 1.778)
			)
			(stroke
				(width 0)
				(type default)
			)
			(fill no)
			(layer "F.Fab")
		)
		(pad "1" smd rect
			(at 0 -0.9652)
			(size 1.397 1.143)
			(layers "F.Cu" "F.Mask" "F.Paste")
			(net "DUT_VDD")
		)
		(pad "2" smd rect
			(at 0 0.9652)
			(size 1.397 1.143)
			(layers "F.Cu" "F.Mask" "F.Paste")
			(net "GND")
		)
	)
)
